(kicad_pcb
	(version 20260206)
	(generator "pcbnew")
	(generator_version "10.0")
	(general
		(thickness 1.6)
		(legacy_teardrops no)
	)
	(paper "A4")
	(title_block
		(title "Bryce Canyon_R.DPB_16317-1_OCP.brd")
		(comment 1 "Bryce Canyon / footprints 1121-1127 of 2099")
	)
	(layers
		(0 "F.Cu" signal "TOP")
		(4 "In1.Cu" signal "L2GND")
		(6 "In2.Cu" signal "L3")
		(8 "In3.Cu" signal "L4VCC")
		(10 "In4.Cu" signal "L5VCC")
		(12 "In5.Cu" signal "L6")
		(14 "In6.Cu" signal "L7GND")
		(2 "B.Cu" signal "BOTTOM")
		(9 "F.Adhes" user "F.Adhesive")
		(11 "B.Adhes" user "B.Adhesive")
		(13 "F.Paste" user "Package Geometry/Pastemask Top")
		(15 "B.Paste" user "Package Geometry/Pastemask Bottom")
		(5 "F.SilkS" user "Ref Des/Silkscreen Top")
		(7 "B.SilkS" user "Ref Des/Silkscreen Bottom")
		(1 "F.Mask" user "Board Geometry/Soldermask Top")
		(3 "B.Mask" user "Board Geometry/Soldermask Bottom")
		(17 "Dwgs.User" user "User.Drawings")
		(19 "Cmts.User" user "User.Comments")
		(21 "Eco1.User" user "User.Eco1")
		(23 "Eco2.User" user "User.Eco2")
		(25 "Edge.Cuts" user "Board Geometry/Outline")
		(27 "Margin" user)
		(31 "F.CrtYd" user "Package Geometry/Place Bound Top")
		(29 "B.CrtYd" user "Package Geometry/Place Bound Bottom")
		(35 "F.Fab" user "Ref Des/Assembly Top")
		(33 "B.Fab" user "Ref Des/Assembly Bottom")
	)
	(footprint ""
		(layer "F.Cu")
		(at 282.984448 -347.541342 180)
		(property "Reference" "R1081"
			(at 0 0 180)
			(layer "F.SilkS")
			(hide yes)
			(effects
				(font
					(size 1.27 1.27)
				)
			)
		)
		(property "Value" "0R2J-2-GP"
			(at 0.064008 -3.993896 180)
			(unlocked yes)
			(layer "F.Fab")
			(hide yes)
			(effects
				(font
					(size 1.016 1.016)
					(thickness 0.1524)
				)
			)
		)
		(property "Device Type" "R402H16"
			(at 0.064008 -5.517896 180)
			(unlocked yes)
			(layer "F.Fab")
			(hide yes)
			(effects
				(font
					(size 1.016 1.016)
					(thickness 0.1524)
				)
			)
		)
		(duplicate_pad_numbers_are_jumpers no)
		(fp_line
			(start 0.508 -0.9398)
			(end -0.508 -0.9398)
			(stroke
				(width 0.1524)
				(type default)
			)
			(layer "F.SilkS")
		)
		(fp_line
			(start -0.508 -0.9398)
			(end -0.508 0.9398)
			(stroke
				(width 0.1524)
				(type default)
			)
			(layer "F.SilkS")
		)
		(fp_rect
			(start -0.508 0.9398)
			(end 0.508 -0.9398)
			(stroke
				(width 0)
				(type default)
			)
			(fill no)
			(layer "F.CrtYd")
		)
		(fp_rect
			(start -0.508 0.9398)
			(end 0.508 -0.9398)
			(stroke
				(width 0)
				(type default)
			)
			(fill no)
			(layer "F.Fab")
		)
		(pad "1" smd custom
			(at 0 -0.4445 180)
			(size 0.1397 0.1397)
			(layers "F.Cu" "F.Mask" "F.Paste")
			(net "GND")
			(options
				(clearance outline)
				(anchor circle)
			)
			(primitives
				(gr_poly
					(pts
						(arc
							(start -0.1778 -0.2794)
							(mid -0.249642 -0.249642)
							(end -0.2794 -0.1778)
						)
						(arc
							(start -0.2794 0.1778)
							(mid -0.249642 0.249642)
							(end -0.1778 0.2794)
						)
						(arc
							(start 0.1778 0.2794)
							(mid 0.249642 0.249642)
							(end 0.2794 0.1778)
						)
						(arc
							(start 0.2794 -0.1778)
							(mid 0.249642 -0.249642)
							(end 0.1778 -0.2794)
						)
					)
					(width 0)
					(fill yes)
				)
			)
		)
		(pad "2" smd custom
			(at 0 0.4445 180)
			(size 0.1397 0.1397)
			(layers "F.Cu" "F.Mask" "F.Paste")
			(net "MAX31790_B_FREQ_ST")
			(options
				(clearance outline)
				(anchor circle)
			)
			(primitives
				(gr_poly
					(pts
						(arc
							(start -0.1778 -0.2794)
							(mid -0.249642 -0.249642)
							(end -0.2794 -0.1778)
						)
						(arc
							(start -0.2794 0.1778)
							(mid -0.249642 0.249642)
							(end -0.1778 0.2794)
						)
						(arc
							(start 0.1778 0.2794)
							(mid 0.249642 0.249642)
							(end 0.2794 0.1778)
						)
						(arc
							(start 0.2794 -0.1778)
							(mid 0.249642 -0.249642)
							(end 0.1778 -0.2794)
						)
					)
					(width 0)
					(fill yes)
				)
			)
		)
	)
	(footprint ""
		(layer "F.Cu")
		(at 235.52404 -233.01198)
		(property "Reference" "R62"
			(at 0 0 0)
			(layer "F.SilkS")
			(hide yes)
			(effects
				(font
					(size 1.27 1.27)
				)
			)
		)
		(property "Value" "4K7R2F-GP"
			(at 0.064008 -3.993896 0)
			(unlocked yes)
			(layer "F.Fab")
			(hide yes)
			(effects
				(font
					(size 1.016 1.016)
					(thickness 0.1524)
				)
			)
		)
		(property "Device Type" "R402H16"
			(at 0.064008 -5.517896 0)
			(unlocked yes)
			(layer "F.Fab")
			(hide yes)
			(effects
				(font
					(size 1.016 1.016)
					(thickness 0.1524)
				)
			)
		)
		(duplicate_pad_numbers_are_jumpers no)
		(fp_line
			(start -0.508 -0.9398)
			(end -0.508 0.9398)
			(stroke
				(width 0.1524)
				(type default)
			)
			(layer "F.SilkS")
		)
		(fp_line
			(start 0.508 -0.9398)
			(end -0.508 -0.9398)
			(stroke
				(width 0.1524)
				(type default)
			)
			(layer "F.SilkS")
		)
		(fp_rect
			(start -0.508 0.9398)
			(end 0.508 -0.9398)
			(stroke
				(width 0)
				(type default)
			)
			(fill no)
			(layer "F.CrtYd")
		)
		(fp_rect
			(start -0.508 0.9398)
			(end 0.508 -0.9398)
			(stroke
				(width 0)
				(type default)
			)
			(fill no)
			(layer "F.Fab")
		)
		(pad "1" smd custom
			(at 0 -0.4445)
			(size 0.1397 0.1397)
			(layers "F.Cu" "F.Mask" "F.Paste")
			(net "P3V3_STBY_B")
			(options
				(clearance outline)
				(anchor circle)
			)
			(primitives
				(gr_poly
					(pts
						(arc
							(start -0.1778 -0.2794)
							(mid -0.249642 -0.249642)
							(end -0.2794 -0.1778)
						)
						(arc
							(start -0.2794 0.1778)
							(mid -0.249642 0.249642)
							(end -0.1778 0.2794)
						)
						(arc
							(start 0.1778 0.2794)
							(mid 0.249642 0.249642)
							(end 0.2794 0.1778)
						)
						(arc
							(start 0.2794 -0.1778)
							(mid 0.249642 -0.249642)
							(end 0.1778 -0.2794)
						)
					)
					(width 0)
					(fill yes)
				)
			)
		)
		(pad "2" smd custom
			(at 0 0.4445)
			(size 0.1397 0.1397)
			(layers "F.Cu" "F.Mask" "F.Paste")
			(net "IO_EXP1_INT_N")
			(options
				(clearance outline)
				(anchor circle)
			)
			(primitives
				(gr_poly
					(pts
						(arc
							(start -0.1778 -0.2794)
							(mid -0.249642 -0.249642)
							(end -0.2794 -0.1778)
						)
						(arc
							(start -0.2794 0.1778)
							(mid -0.249642 0.249642)
							(end -0.1778 0.2794)
						)
						(arc
							(start 0.1778 0.2794)
							(mid 0.249642 0.249642)
							(end 0.2794 0.1778)
						)
						(arc
							(start 0.2794 -0.1778)
							(mid 0.249642 -0.249642)
							(end 0.1778 -0.2794)
						)
					)
					(width 0)
					(fill yes)
				)
			)
		)
	)
	(footprint ""
		(layer "F.Cu")
		(at 476.9866 -135.7884 90)
		(property "Reference" "C335"
			(at 0 0 90)
			(layer "F.SilkS")
			(hide yes)
			(effects
				(font
					(size 1.27 1.27)
				)
			)
		)
		(property "Value" "SCD01U50V2KX-1GP"
			(at 1.1811 -2.7051 90)
			(unlocked yes)
			(layer "F.Fab")
			(hide yes)
			(effects
				(font
					(size 1.016 1.016)
					(thickness 0.1524)
				)
			)
		)
		(property "Device Type" "C402H22"
			(at 1.1811 -4.2291 90)
			(unlocked yes)
			(layer "F.Fab")
			(hide yes)
			(effects
				(font
					(size 1.016 1.016)
					(thickness 0.1524)
				)
			)
		)
		(duplicate_pad_numbers_are_jumpers no)
		(fp_rect
			(start -0.4318 0.9525)
			(end 0.4318 -0.9525)
			(stroke
				(width 0)
				(type default)
			)
			(fill no)
			(layer "F.CrtYd")
		)
		(fp_rect
			(start -0.4318 0.9525)
			(end 0.4318 -0.9525)
			(stroke
				(width 0)
				(type default)
			)
			(fill no)
			(layer "F.Fab")
		)
		(pad "1" smd custom
			(at 0 -0.4445 90)
			(size 0.1524 0.1524)
			(layers "F.Cu" "F.Mask" "F.Paste")
			(net "HDD_PRSNT_23")
			(options
				(clearance outline)
				(anchor circle)
			)
			(primitives
				(gr_poly
					(pts
						(arc
							(start 0.3048 -0.2032)
							(mid 0.275042 -0.275042)
							(end 0.2032 -0.3048)
						)
						(arc
							(start -0.2032 -0.3048)
							(mid -0.275042 -0.275042)
							(end -0.3048 -0.2032)
						)
						(arc
							(start -0.3048 0.2032)
							(mid -0.275042 0.275042)
							(end -0.2032 0.3048)
						)
						(arc
							(start 0.2032 0.3048)
							(mid 0.275042 0.275042)
							(end 0.3048 0.2032)
						)
					)
					(width 0)
					(fill yes)
				)
			)
		)
		(pad "2" smd custom
			(at 0 0.4445 90)
			(size 0.1524 0.1524)
			(layers "F.Cu" "F.Mask" "F.Paste")
			(net "GND")
			(options
				(clearance outline)
				(anchor circle)
			)
			(primitives
				(gr_poly
					(pts
						(arc
							(start 0.3048 -0.2032)
							(mid 0.275042 -0.275042)
							(end 0.2032 -0.3048)
						)
						(arc
							(start -0.2032 -0.3048)
							(mid -0.275042 -0.275042)
							(end -0.3048 -0.2032)
						)
						(arc
							(start -0.3048 0.2032)
							(mid -0.275042 0.275042)
							(end -0.2032 0.3048)
						)
						(arc
							(start 0.2032 0.3048)
							(mid 0.275042 0.275042)
							(end 0.3048 0.2032)
						)
					)
					(width 0)
					(fill yes)
				)
			)
		)
	)
	(footprint ""
		(layer "F.Cu")
		(at 51.562 -146.939 -90)
		(property "Reference" "C200"
			(at 0 0 270)
			(layer "F.SilkS")
			(hide yes)
			(effects
				(font
					(size 1.27 1.27)
				)
			)
		)
		(property "Value" "SC10U16V6KX-2GP"
			(at -0.0762 -5.1308 270)
			(unlocked yes)
			(layer "F.Fab")
			(hide yes)
			(effects
				(font
					(size 1.016 1.016)
					(thickness 0.1524)
				)
			)
		)
		(property "Device Type" "C1206H71"
			(at -0.127 -6.6548 270)
			(unlocked yes)
			(layer "F.Fab")
			(hide yes)
			(effects
				(font
					(size 1.016 1.016)
					(thickness 0.1524)
				)
			)
		)
		(duplicate_pad_numbers_are_jumpers no)
		(fp_line
			(start -1.016 2.2352)
			(end -1.016 0.8382)
			(stroke
				(width 0.1524)
				(type default)
			)
			(layer "F.SilkS")
		)
		(fp_line
			(start 1.016 2.2352)
			(end -1.016 2.2352)
			(stroke
				(width 0.1524)
				(type default)
			)
			(layer "F.SilkS")
		)
		(fp_line
			(start 1.016 0.8382)
			(end 1.016 2.2352)
			(stroke
				(width 0.1524)
				(type default)
			)
			(layer "F.SilkS")
		)
		(fp_line
			(start -1.016 -0.8382)
			(end -1.016 -2.2352)
			(stroke
				(width 0.1524)
				(type default)
			)
			(layer "F.SilkS")
		)
		(fp_line
			(start -1.016 -2.2352)
			(end 1.016 -2.2352)
			(stroke
				(width 0.1524)
				(type default)
			)
			(layer "F.SilkS")
		)
		(fp_line
			(start 1.016 -2.2352)
			(end 1.016 -0.8382)
			(stroke
				(width 0.1524)
				(type default)
			)
			(layer "F.SilkS")
		)
		(fp_rect
			(start -1.0922 2.3114)
			(end 1.0922 -2.3114)
			(stroke
				(width 0)
				(type default)
			)
			(fill no)
			(layer "F.CrtYd")
		)
		(fp_poly
			(pts
				(xy 1.0922 -2.3114) (xy 1.0922 2.3114) (xy -1.0922 2.3114) (xy -1.0922 -2.3114)
			)
			(stroke
				(width 0)
				(type default)
			)
			(fill no)
			(layer "F.Fab")
		)
		(pad "1" smd rect
			(at 0 -1.397 270)
			(size 1.651 1.27)
			(layers "F.Cu" "F.Mask" "F.Paste")
			(net "P5V_HDD13")
		)
		(pad "2" smd rect
			(at 0 1.397 270)
			(size 1.651 1.27)
			(layers "F.Cu" "F.Mask" "F.Paste")
			(net "GND")
		)
	)
	(footprint ""
		(layer "F.Cu")
		(at 440.69 -214.249)
		(property "Reference" "R364"
			(at 0 0 0)
			(layer "F.SilkS")
			(hide yes)
			(effects
				(font
					(size 1.27 1.27)
				)
			)
		)
		(property "Value" "130R3F-GP"
			(at -0.0254 -2.5146 0)
			(unlocked yes)
			(layer "F.Fab")
			(hide yes)
			(effects
				(font
					(size 1.016 1.016)
					(thickness 0.1524)
				)
			)
		)
		(property "Device Type" "R603H22"
			(at -0.0254 -4.0386 0)
			(unlocked yes)
			(layer "F.Fab")
			(hide yes)
			(effects
				(font
					(size 1.016 1.016)
					(thickness 0.1524)
				)
			)
		)
		(duplicate_pad_numbers_are_jumpers no)
		(fp_line
			(start -0.4826 0)
			(end -0.2032 0)
			(stroke
				(width 0.2032)
				(type default)
			)
			(layer "F.SilkS")
		)
		(fp_line
			(start 0.2032 0)
			(end 0.4826 0)
			(stroke
				(width 0.2032)
				(type default)
			)
			(layer "F.SilkS")
		)
		(fp_rect
			(start -0.5842 1.3335)
			(end 0.5842 -1.3335)
			(stroke
				(width 0)
				(type default)
			)
			(fill no)
			(layer "F.CrtYd")
		)
		(fp_rect
			(start -0.5842 1.3335)
			(end 0.5842 -1.3335)
			(stroke
				(width 0)
				(type default)
			)
			(fill no)
			(layer "F.Fab")
		)
		(pad "1" smd custom
			(at 0 -0.762)
			(size 0.2159 0.2159)
			(layers "F.Cu" "F.Mask" "F.Paste")
			(net "P5V_B_3")
			(options
				(clearance outline)
				(anchor circle)
			)
			(primitives
				(gr_poly
					(pts
						(arc
							(start -0.3302 -0.4318)
							(mid -0.402042 -0.402042)
							(end -0.4318 -0.3302)
						)
						(arc
							(start -0.4318 0.3302)
							(mid -0.402042 0.402042)
							(end -0.3302 0.4318)
						)
						(arc
							(start 0.3302 0.4318)
							(mid 0.402042 0.402042)
							(end 0.4318 0.3302)
						)
						(arc
							(start 0.4318 -0.3302)
							(mid 0.402042 -0.402042)
							(end 0.3302 -0.4318)
						)
					)
					(width 0)
					(fill yes)
				)
			)
		)
		(pad "2" smd custom
			(at 0 0.762)
			(size 0.2159 0.2159)
			(layers "F.Cu" "F.Mask" "F.Paste")
			(net "FLT_HDD10")
			(options
				(clearance outline)
				(anchor circle)
			)
			(primitives
				(gr_poly
					(pts
						(arc
							(start -0.3302 -0.4318)
							(mid -0.402042 -0.402042)
							(end -0.4318 -0.3302)
						)
						(arc
							(start -0.4318 0.3302)
							(mid -0.402042 0.402042)
							(end -0.3302 0.4318)
						)
						(arc
							(start 0.3302 0.4318)
							(mid 0.402042 0.402042)
							(end 0.4318 0.3302)
						)
						(arc
							(start 0.4318 -0.3302)
							(mid 0.402042 -0.402042)
							(end 0.3302 -0.4318)
						)
					)
					(width 0)
					(fill yes)
				)
			)
		)
	)
	(footprint ""
		(layer "F.Cu")
		(at 392.938 -275.336 180)
		(property "Reference" "C140"
			(at 0 0 180)
			(layer "F.SilkS")
			(hide yes)
			(effects
				(font
					(size 1.27 1.27)
				)
			)
		)
		(property "Value" "SC1U25V3KX-GP"
			(at 0 -2.8194 180)
			(unlocked yes)
			(layer "F.Fab")
			(hide yes)
			(effects
				(font
					(size 1.016 1.016)
					(thickness 0.1524)
				)
			)
		)
		(property "Device Type" "C603H36"
			(at 0 -4.3434 180)
			(unlocked yes)
			(layer "F.Fab")
			(hide yes)
			(effects
				(font
					(size 1.016 1.016)
					(thickness 0.1524)
				)
			)
		)
		(duplicate_pad_numbers_are_jumpers no)
		(fp_line
			(start 0.508 0)
			(end -0.508 0)
			(stroke
				(width 0.2032)
				(type default)
			)
			(layer "F.SilkS")
		)
		(fp_rect
			(start -0.5842 1.3335)
			(end 0.5842 -1.3335)
			(stroke
				(width 0)
				(type default)
			)
			(fill no)
			(layer "F.CrtYd")
		)
		(fp_rect
			(start -0.5842 1.3335)
			(end 0.5842 -1.3335)
			(stroke
				(width 0)
				(type default)
			)
			(fill no)
			(layer "F.Fab")
		)
		(pad "1" smd custom
			(at 0 -0.762 180)
			(size 0.2159 0.2159)
			(layers "F.Cu" "F.Mask" "F.Paste")
			(net "P12V_HDD8")
			(options
				(clearance outline)
				(anchor circle)
			)
			(primitives
				(gr_poly
					(pts
						(arc
							(start -0.3302 -0.4318)
							(mid -0.402042 -0.402042)
							(end -0.4318 -0.3302)
						)
						(arc
							(start -0.4318 0.3302)
							(mid -0.402042 0.402042)
							(end -0.3302 0.4318)
						)
						(arc
							(start 0.3302 0.4318)
							(mid 0.402042 0.402042)
							(end 0.4318 0.3302)
						)
						(arc
							(start 0.4318 -0.3302)
							(mid 0.402042 -0.402042)
							(end 0.3302 -0.4318)
						)
					)
					(width 0)
					(fill yes)
				)
			)
		)
		(pad "2" smd custom
			(at 0 0.762 180)
			(size 0.2159 0.2159)
			(layers "F.Cu" "F.Mask" "F.Paste")
			(net "GND")
			(options
				(clearance outline)
				(anchor circle)
			)
			(primitives
				(gr_poly
					(pts
						(arc
							(start -0.3302 -0.4318)
							(mid -0.402042 -0.402042)
							(end -0.4318 -0.3302)
						)
						(arc
							(start -0.4318 0.3302)
							(mid -0.402042 0.402042)
							(end -0.3302 0.4318)
						)
						(arc
							(start 0.3302 0.4318)
							(mid 0.402042 0.402042)
							(end 0.4318 0.3302)
						)
						(arc
							(start 0.4318 -0.3302)
							(mid 0.402042 -0.402042)
							(end 0.3302 -0.4318)
						)
					)
					(width 0)
					(fill yes)
				)
			)
		)
	)
	(footprint ""
		(layer "F.Cu")
		(at 266.192 -226.568)
		(property "Reference" "R8"
			(at 0 0 0)
			(layer "F.SilkS")
			(hide yes)
			(effects
				(font
					(size 1.27 1.27)
				)
			)
		)
		(property "Value" "1KR2F-3-GP"
			(at 0.064008 -3.993896 0)
			(unlocked yes)
			(layer "F.Fab")
			(hide yes)
			(effects
				(font
					(size 1.016 1.016)
					(thickness 0.1524)
				)
			)
		)
		(property "Device Type" "R402H16"
			(at 0.064008 -5.517896 0)
			(unlocked yes)
			(layer "F.Fab")
			(hide yes)
			(effects
				(font
					(size 1.016 1.016)
					(thickness 0.1524)
				)
			)
		)
		(duplicate_pad_numbers_are_jumpers no)
		(fp_line
			(start -0.508 -0.9398)
			(end -0.508 0.9398)
			(stroke
				(width 0.1524)
				(type default)
			)
			(layer "F.SilkS")
		)
		(fp_line
			(start 0.508 -0.9398)
			(end -0.508 -0.9398)
			(stroke
				(width 0.1524)
				(type default)
			)
			(layer "F.SilkS")
		)
		(fp_rect
			(start -0.508 0.9398)
			(end 0.508 -0.9398)
			(stroke
				(width 0)
				(type default)
			)
			(fill no)
			(layer "F.CrtYd")
		)
		(fp_rect
			(start -0.508 0.9398)
			(end 0.508 -0.9398)
			(stroke
				(width 0)
				(type default)
			)
			(fill no)
			(layer "F.Fab")
		)
		(pad "1" smd custom
			(at 0 -0.4445)
			(size 0.1397 0.1397)
			(layers "F.Cu" "F.Mask" "F.Paste")
			(net "P3V3_IN")
			(options
				(clearance outline)
				(anchor circle)
			)
			(primitives
				(gr_poly
					(pts
						(arc
							(start -0.1778 -0.2794)
							(mid -0.249642 -0.249642)
							(end -0.2794 -0.1778)
						)
						(arc
							(start -0.2794 0.1778)
							(mid -0.249642 0.249642)
							(end -0.1778 0.2794)
						)
						(arc
							(start 0.1778 0.2794)
							(mid 0.249642 0.249642)
							(end 0.2794 0.1778)
						)
						(arc
							(start 0.2794 -0.1778)
							(mid 0.249642 -0.249642)
							(end 0.1778 -0.2794)
						)
					)
					(width 0)
					(fill yes)
				)
			)
		)
		(pad "2" smd custom
			(at 0 0.4445)
			(size 0.1397 0.1397)
			(layers "F.Cu" "F.Mask" "F.Paste")
			(net "I2C_CLIP_B_SCL")
			(options
				(clearance outline)
				(anchor circle)
			)
			(primitives
				(gr_poly
					(pts
						(arc
							(start -0.1778 -0.2794)
							(mid -0.249642 -0.249642)
							(end -0.2794 -0.1778)
						)
						(arc
							(start -0.2794 0.1778)
							(mid -0.249642 0.249642)
							(end -0.1778 0.2794)
						)
						(arc
							(start 0.1778 0.2794)
							(mid 0.249642 0.249642)
							(end 0.2794 0.1778)
						)
						(arc
							(start 0.2794 -0.1778)
							(mid 0.249642 -0.249642)
							(end 0.1778 -0.2794)
						)
					)
					(width 0)
					(fill yes)
				)
			)
		)
	)
)
